# SCM (Grand Teton) — schematic netlist excerpt (pin names and nets, part order shuffled) for the footprints in the layout excerpt that follows; sources: Cadence DE-HDL packaged netlist, KiCad conversion of 12092022_DA0F0TMDCD0_F0T_Management_Board_D_brd_V3_OCP.brd

Q3  MMBT39047F  MMBT3904-7-F IC  pkg SOT23_BEC  page 22
  \1\  = BJT_Q3_B
  \3\  = BJT_Q3_C
  \2\  = GND

R57  Q_RES  0 5% CHIP  pkg 0402LF  page 21 : A = BSM_PRSNT_R_N ; B = BSM_PRSNT_N

(kicad_pcb
	(version 20260206)
	(generator "pcbnew")
	(generator_version "10.0")
	(general
		(thickness 1.6)
		(legacy_teardrops no)
	)
	(paper "A4")
	(title_block
		(title "12092022_DA0F0TMDCD0_F0T_Management_Board_D_brd_V3_OCP.brd")
		(comment 1 "Grand Teton / footprints 105-106 of 1440")
	)
	(layers
		(0 "F.Cu" signal "TOP")
		(4 "In1.Cu" signal "GND")
		(6 "In2.Cu" signal "IN1")
		(8 "In3.Cu" signal "GND1")
		(10 "In4.Cu" signal "IN2")
		(12 "In5.Cu" signal "VCC")
		(14 "In6.Cu" signal "VCC1")
		(16 "In7.Cu" signal "IN3")
		(18 "In8.Cu" signal "GND2")
		(20 "In9.Cu" signal "IN4")
		(22 "In10.Cu" signal "GND3")
		(2 "B.Cu" signal "BOTTOM")
		(9 "F.Adhes" user "F.Adhesive")
		(11 "B.Adhes" user "B.Adhesive")
		(13 "F.Paste" user "Package Geometry/Pastemask Top")
		(15 "B.Paste" user "Package Geometry/Pastemask Bottom")
		(5 "F.SilkS" user "Ref Des/Silkscreen Top")
		(7 "B.SilkS" user "Ref Des/Silkscreen Bottom")
		(1 "F.Mask" user "Board Geometry/Soldermask Top")
		(3 "B.Mask" user "Board Geometry/Soldermask Bottom")
		(17 "Dwgs.User" user "User.Drawings")
		(19 "Cmts.User" user "User.Comments")
		(21 "Eco1.User" user "User.Eco1")
		(23 "Eco2.User" user "User.Eco2")
		(25 "Edge.Cuts" user "Board Geometry/Outline")
		(27 "Margin" user)
		(31 "F.CrtYd" user "Package Geometry/Place Bound Top")
		(29 "B.CrtYd" user "Package Geometry/Place Bound Bottom")
		(35 "F.Fab" user "Ref Des/Assembly Top")
		(33 "B.Fab" user "Ref Des/Assembly Bottom")
	)
	(footprint ""
		(layer "F.Cu")
		(at 23.241 -68.834 90)
		(property "Reference" "R57"
			(at 0 0 90)
			(layer "F.SilkS")
			(hide yes)
			(effects
				(font
					(size 1.27 1.27)
				)
			)
		)
		(property "Value" ""
			(at 0 0 90)
			(layer "F.Fab")
			(effects
				(font
					(size 1.27 1.27)
				)
			)
		)
		(duplicate_pad_numbers_are_jumpers no)
		(fp_line
			(start 0.7874 -0.4064)
			(end 0.7874 0.4064)
			(stroke
				(width 0.1524)
				(type default)
			)
			(layer "F.SilkS")
		)
		(fp_line
			(start -0.7874 -0.4064)
			(end 0.7874 -0.4064)
			(stroke
				(width 0.1524)
				(type default)
			)
			(layer "F.SilkS")
		)
		(fp_line
			(start 0.7874 0.4064)
			(end -0.7874 0.4064)
			(stroke
				(width 0.1524)
				(type default)
			)
			(layer "F.SilkS")
		)
		(fp_line
			(start -0.7874 0.4064)
			(end -0.7874 -0.4064)
			(stroke
				(width 0.1524)
				(type default)
			)
			(layer "F.SilkS")
		)
		(fp_line
			(start -0.12065 -0.305054)
			(end -0.12065 -0.2794)
			(stroke
				(width 0.1)
				(type default)
			)
			(layer "F.Fab")
		)
		(fp_line
			(start -0.67945 -0.305054)
			(end -0.12065 -0.305054)
			(stroke
				(width 0.1)
				(type default)
			)
			(layer "F.Fab")
		)
		(fp_line
			(start 0.67945 -0.3048)
			(end 0.67945 0.3048)
			(stroke
				(width 0.1)
				(type default)
			)
			(layer "F.Fab")
		)
		(fp_line
			(start 0.12065 -0.3048)
			(end 0.67945 -0.3048)
			(stroke
				(width 0.1)
				(type default)
			)
			(layer "F.Fab")
		)
		(fp_line
			(start 0.12065 -0.2794)
			(end 0.12065 -0.3048)
			(stroke
				(width 0.1)
				(type default)
			)
			(layer "F.Fab")
		)
		(fp_line
			(start -0.12065 -0.2794)
			(end 0.12065 -0.2794)
			(stroke
				(width 0.1)
				(type default)
			)
			(layer "F.Fab")
		)
		(fp_line
			(start 0.120396 0.2794)
			(end -0.12065 0.2794)
			(stroke
				(width 0.1)
				(type default)
			)
			(layer "F.Fab")
		)
		(fp_line
			(start -0.12065 0.2794)
			(end -0.12065 0.3048)
			(stroke
				(width 0.1)
				(type default)
			)
			(layer "F.Fab")
		)
		(fp_line
			(start 0.67945 0.3048)
			(end 0.120396 0.3048)
			(stroke
				(width 0.1)
				(type default)
			)
			(layer "F.Fab")
		)
		(fp_line
			(start 0.120396 0.3048)
			(end 0.120396 0.2794)
			(stroke
				(width 0.1)
				(type default)
			)
			(layer "F.Fab")
		)
		(fp_line
			(start -0.12065 0.3048)
			(end -0.67945 0.3048)
			(stroke
				(width 0.1)
				(type default)
			)
			(layer "F.Fab")
		)
		(fp_line
			(start -0.67945 0.3048)
			(end -0.67945 -0.305054)
			(stroke
				(width 0.1)
				(type default)
			)
			(layer "F.Fab")
		)
		(pad "1" smd circle
			(at -0.40005 0 90)
			(size 0 0)
			(layers "F.Cu" "F.Mask" "F.Paste")
			(net "BSM_PRSNT_R_N")
		)
		(pad "2" smd circle
			(at 0.40005 0 90)
			(size 0 0)
			(layers "F.Cu" "F.Mask" "F.Paste")
			(net "BSM_PRSNT_N")
		)
	)
	(footprint ""
		(layer "F.Cu")
		(at 51.7525 -92.837 90)
		(property "Reference" "Q3"
			(at 1.29413 2.2225 0)
			(unlocked yes)
			(layer "F.SilkS")
			(effects
				(font
					(size 0.7874 0.5842)
					(thickness 0.1524)
				)
				(justify left)
			)
		)
		(property "Value" ""
			(at 0 0 90)
			(layer "F.Fab")
			(effects
				(font
					(size 1.27 1.27)
				)
			)
		)
		(duplicate_pad_numbers_are_jumpers no)
		(fp_line
			(start 1.905 -1.651)
			(end 1.905 1.651)
			(stroke
				(width 0.1524)
				(type default)
			)
			(layer "F.SilkS")
		)
		(fp_line
			(start -1.905 -1.651)
			(end 1.905 -1.651)
			(stroke
				(width 0.1524)
				(type default)
			)
			(layer "F.SilkS")
		)
		(fp_line
			(start 1.905 1.651)
			(end -1.905 1.651)
			(stroke
				(width 0.1524)
				(type default)
			)
			(layer "F.SilkS")
		)
		(fp_line
			(start -1.905 1.651)
			(end -1.905 -1.651)
			(stroke
				(width 0.1524)
				(type default)
			)
			(layer "F.SilkS")
		)
		(fp_line
			(start 0.6985 -1.524)
			(end 0.6985 -0.219964)
			(stroke
				(width 0.1)
				(type default)
			)
			(layer "F.Fab")
		)
		(fp_line
			(start -0.649986 -1.524)
			(end 0.6985 -1.524)
			(stroke
				(width 0.1)
				(type default)
			)
			(layer "F.Fab")
		)
		(fp_line
			(start -0.649986 -1.169924)
			(end -0.649986 -1.524)
			(stroke
				(width 0.1)
				(type default)
			)
			(layer "F.Fab")
		)
		(fp_line
			(start -1.249934 -1.169924)
			(end -0.649986 -1.169924)
			(stroke
				(width 0.1)
				(type default)
			)
			(layer "F.Fab")
		)
		(fp_line
			(start -0.6985 -0.729996)
			(end -1.249934 -0.729996)
			(stroke
				(width 0.1)
				(type default)
			)
			(layer "F.Fab")
		)
		(fp_line
			(start -1.249934 -0.729996)
			(end -1.249934 -1.169924)
			(stroke
				(width 0.1)
				(type default)
			)
			(layer "F.Fab")
		)
		(fp_line
			(start 1.249934 -0.219964)
			(end 1.249934 0.219964)
			(stroke
				(width 0.1)
				(type default)
			)
			(layer "F.Fab")
		)
		(fp_line
			(start 0.6985 -0.219964)
			(end 1.249934 -0.219964)
			(stroke
				(width 0.1)
				(type default)
			)
			(layer "F.Fab")
		)
		(fp_line
			(start 1.249934 0.219964)
			(end 0.6985 0.219964)
			(stroke
				(width 0.1)
				(type default)
			)
			(layer "F.Fab")
		)
		(fp_line
			(start 0.6985 0.219964)
			(end 0.6985 1.524)
			(stroke
				(width 0.1)
				(type default)
			)
			(layer "F.Fab")
		)
		(fp_line
			(start -0.6985 0.729996)
			(end -0.6985 -0.729996)
			(stroke
				(width 0.1)
				(type default)
			)
			(layer "F.Fab")
		)
		(fp_line
			(start -1.249934 0.729996)
			(end -0.6985 0.729996)
			(stroke
				(width 0.1)
				(type default)
			)
			(layer "F.Fab")
		)
		(fp_line
			(start -0.649986 1.169924)
			(end -1.249934 1.169924)
			(stroke
				(width 0.1)
				(type default)
			)
			(layer "F.Fab")
		)
		(fp_line
			(start -1.249934 1.169924)
			(end -1.249934 0.729996)
			(stroke
				(width 0.1)
				(type default)
			)
			(layer "F.Fab")
		)
		(fp_line
			(start 0.6985 1.524)
			(end -0.649986 1.524)
			(stroke
				(width 0.1)
				(type default)
			)
			(layer "F.Fab")
		)
		(fp_line
			(start -0.649986 1.524)
			(end -0.649986 1.169924)
			(stroke
				(width 0.1)
				(type default)
			)
			(layer "F.Fab")
		)
		(pad "B" smd rect
			(at -1.1176 -1.016)
			(size 1.016 1.27)
			(layers "F.Cu" "F.Mask" "F.Paste")
			(net "BJT_Q3_B")
		)
		(pad "C" smd rect
			(at 1.1176 0)
			(size 1.016 1.27)
			(layers "F.Cu" "F.Mask" "F.Paste")
			(net "BJT_Q3_C")
		)
		(pad "E" smd rect
			(at -1.1176 1.016)
			(size 1.016 1.27)
			(layers "F.Cu" "F.Mask" "F.Paste")
			(net "GND")
		)
	)
)
